# T6G (Grand Teton) — schematic netlist excerpt (pin names and nets, part order shuffled) for the footprints in the layout excerpt that follows; sources: Cadence DE-HDL packaged netlist, KiCad conversion of 04192023_DAF0TMB3IC0_F0TG_MB_C_brd_V02_OCP.brd

R1396  Q_RES  10K 1% CHIP  pkg 0402LF  page 144 : A = FM_M2_SSD_0_PEDET ; B = P3V3_AUX
R3315  Q_RES  33.2 1% CHIP  pkg 0402LF  page 130 : A = GPU_FPGA_RST_R1_BUF_N ; B = GPU_FPGA_RST_R_BUF_N

(kicad_pcb
	(version 20260206)
	(generator "pcbnew")
	(generator_version "10.0")
	(general
		(thickness 1.6)
		(legacy_teardrops no)
	)
	(paper "A4")
	(title_block
		(title "04192023_DAF0TMB3IC0_F0TG_MB_C_brd_V02_OCP.brd")
		(comment 1 "Grand Teton / footprints 4627-4628 of 8354")
	)
	(layers
		(0 "F.Cu" signal "TOP")
		(4 "In1.Cu" signal "GND")
		(6 "In2.Cu" signal "IN1")
		(8 "In3.Cu" signal "GND1")
		(10 "In4.Cu" signal "IN2")
		(12 "In5.Cu" signal "GND2")
		(14 "In6.Cu" signal "IN3")
		(16 "In7.Cu" signal "GND3")
		(18 "In8.Cu" signal "VCC")
		(20 "In9.Cu" signal "VCC1")
		(22 "In10.Cu" signal "GND4")
		(24 "In11.Cu" signal "IN4")
		(26 "In12.Cu" signal "GND5")
		(28 "In13.Cu" signal "IN5")
		(30 "In14.Cu" signal "GND6")
		(32 "In15.Cu" signal "IN6")
		(34 "In16.Cu" signal "GND7")
		(2 "B.Cu" signal "BOTTOM")
		(9 "F.Adhes" user "F.Adhesive")
		(11 "B.Adhes" user "B.Adhesive")
		(13 "F.Paste" user "Package Geometry/Pastemask Top")
		(15 "B.Paste" user "Package Geometry/Pastemask Bottom")
		(5 "F.SilkS" user "Ref Des/Silkscreen Top")
		(7 "B.SilkS" user "Ref Des/Silkscreen Bottom")
		(1 "F.Mask" user "Board Geometry/Soldermask Top")
		(3 "B.Mask" user "Board Geometry/Soldermask Bottom")
		(17 "Dwgs.User" user "User.Drawings")
		(19 "Cmts.User" user "User.Comments")
		(21 "Eco1.User" user "User.Eco1")
		(23 "Eco2.User" user "User.Eco2")
		(25 "Edge.Cuts" user "Board Geometry/Outline")
		(27 "Margin" user)
		(31 "F.CrtYd" user "Package Geometry/Place Bound Top")
		(29 "B.CrtYd" user "Package Geometry/Place Bound Bottom")
		(35 "F.Fab" user "Ref Des/Assembly Top")
		(33 "B.Fab" user "Ref Des/Assembly Bottom")
	)
	(footprint ""
		(layer "F.Cu")
		(at 180.7718 -40.071548)
		(property "Reference" "R1396"
			(at 0 0 0)
			(layer "F.SilkS")
			(hide yes)
			(effects
				(font
					(size 1.27 1.27)
				)
			)
		)
		(property "Value" ""
			(at 0 0 0)
			(layer "F.Fab")
			(effects
				(font
					(size 1.27 1.27)
				)
			)
		)
		(duplicate_pad_numbers_are_jumpers no)
		(fp_line
			(start -0.7874 -0.4064)
			(end 0.7874 -0.4064)
			(stroke
				(width 0.1524)
				(type default)
			)
			(layer "F.SilkS")
		)
		(fp_line
			(start -0.7874 0.4064)
			(end -0.7874 -0.4064)
			(stroke
				(width 0.1524)
				(type default)
			)
			(layer "F.SilkS")
		)
		(fp_line
			(start 0.7874 -0.4064)
			(end 0.7874 0.4064)
			(stroke
				(width 0.1524)
				(type default)
			)
			(layer "F.SilkS")
		)
		(fp_line
			(start 0.7874 0.4064)
			(end -0.7874 0.4064)
			(stroke
				(width 0.1524)
				(type default)
			)
			(layer "F.SilkS")
		)
		(fp_line
			(start -0.67945 -0.305054)
			(end -0.12065 -0.305054)
			(stroke
				(width 0.1)
				(type default)
			)
			(layer "F.Fab")
		)
		(fp_line
			(start -0.67945 0.3048)
			(end -0.67945 -0.305054)
			(stroke
				(width 0.1)
				(type default)
			)
			(layer "F.Fab")
		)
		(fp_line
			(start -0.12065 -0.305054)
			(end -0.12065 -0.2794)
			(stroke
				(width 0.1)
				(type default)
			)
			(layer "F.Fab")
		)
		(fp_line
			(start -0.12065 -0.2794)
			(end 0.12065 -0.2794)
			(stroke
				(width 0.1)
				(type default)
			)
			(layer "F.Fab")
		)
		(fp_line
			(start -0.12065 0.2794)
			(end -0.12065 0.3048)
			(stroke
				(width 0.1)
				(type default)
			)
			(layer "F.Fab")
		)
		(fp_line
			(start -0.12065 0.3048)
			(end -0.67945 0.3048)
			(stroke
				(width 0.1)
				(type default)
			)
			(layer "F.Fab")
		)
		(fp_line
			(start 0.120396 0.2794)
			(end -0.12065 0.2794)
			(stroke
				(width 0.1)
				(type default)
			)
			(layer "F.Fab")
		)
		(fp_line
			(start 0.120396 0.3048)
			(end 0.120396 0.2794)
			(stroke
				(width 0.1)
				(type default)
			)
			(layer "F.Fab")
		)
		(fp_line
			(start 0.12065 -0.3048)
			(end 0.67945 -0.3048)
			(stroke
				(width 0.1)
				(type default)
			)
			(layer "F.Fab")
		)
		(fp_line
			(start 0.12065 -0.2794)
			(end 0.12065 -0.3048)
			(stroke
				(width 0.1)
				(type default)
			)
			(layer "F.Fab")
		)
		(fp_line
			(start 0.67945 -0.3048)
			(end 0.67945 0.3048)
			(stroke
				(width 0.1)
				(type default)
			)
			(layer "F.Fab")
		)
		(fp_line
			(start 0.67945 0.3048)
			(end 0.120396 0.3048)
			(stroke
				(width 0.1)
				(type default)
			)
			(layer "F.Fab")
		)
		(pad "1" smd circle
			(at -0.40005 0)
			(size 0 0)
			(layers "F.Cu" "F.Mask" "F.Paste")
			(net "FM_M2_SSD_0_PEDET")
		)
		(pad "2" smd circle
			(at 0.40005 0)
			(size 0 0)
			(layers "F.Cu" "F.Mask" "F.Paste")
			(net "P3V3_AUX")
		)
	)
	(footprint ""
		(layer "F.Cu")
		(at 48.19904 -434.057552 -90)
		(property "Reference" "R3315"
			(at 0 0 270)
			(layer "F.SilkS")
			(hide yes)
			(effects
				(font
					(size 1.27 1.27)
				)
			)
		)
		(property "Value" ""
			(at 0 0 270)
			(layer "F.Fab")
			(effects
				(font
					(size 1.27 1.27)
				)
			)
		)
		(duplicate_pad_numbers_are_jumpers no)
		(fp_line
			(start -0.7874 0.4064)
			(end -0.7874 -0.4064)
			(stroke
				(width 0.1524)
				(type default)
			)
			(layer "F.SilkS")
		)
		(fp_line
			(start 0.7874 0.4064)
			(end -0.7874 0.4064)
			(stroke
				(width 0.1524)
				(type default)
			)
			(layer "F.SilkS")
		)
		(fp_line
			(start -0.7874 -0.4064)
			(end 0.7874 -0.4064)
			(stroke
				(width 0.1524)
				(type default)
			)
			(layer "F.SilkS")
		)
		(fp_line
			(start 0.7874 -0.4064)
			(end 0.7874 0.4064)
			(stroke
				(width 0.1524)
				(type default)
			)
			(layer "F.SilkS")
		)
		(fp_line
			(start -0.67945 0.3048)
			(end -0.67945 -0.305054)
			(stroke
				(width 0.1)
				(type default)
			)
			(layer "F.Fab")
		)
		(fp_line
			(start -0.12065 0.3048)
			(end -0.67945 0.3048)
			(stroke
				(width 0.1)
				(type default)
			)
			(layer "F.Fab")
		)
		(fp_line
			(start 0.120396 0.3048)
			(end 0.120396 0.2794)
			(stroke
				(width 0.1)
				(type default)
			)
			(layer "F.Fab")
		)
		(fp_line
			(start 0.67945 0.3048)
			(end 0.120396 0.3048)
			(stroke
				(width 0.1)
				(type default)
			)
			(layer "F.Fab")
		)
		(fp_line
			(start -0.12065 0.2794)
			(end -0.12065 0.3048)
			(stroke
				(width 0.1)
				(type default)
			)
			(layer "F.Fab")
		)
		(fp_line
			(start 0.120396 0.2794)
			(end -0.12065 0.2794)
			(stroke
				(width 0.1)
				(type default)
			)
			(layer "F.Fab")
		)
		(fp_line
			(start -0.12065 -0.2794)
			(end 0.12065 -0.2794)
			(stroke
				(width 0.1)
				(type default)
			)
			(layer "F.Fab")
		)
		(fp_line
			(start 0.12065 -0.2794)
			(end 0.12065 -0.3048)
			(stroke
				(width 0.1)
				(type default)
			)
			(layer "F.Fab")
		)
		(fp_line
			(start 0.12065 -0.3048)
			(end 0.67945 -0.3048)
			(stroke
				(width 0.1)
				(type default)
			)
			(layer "F.Fab")
		)
		(fp_line
			(start 0.67945 -0.3048)
			(end 0.67945 0.3048)
			(stroke
				(width 0.1)
				(type default)
			)
			(layer "F.Fab")
		)
		(fp_line
			(start -0.67945 -0.305054)
			(end -0.12065 -0.305054)
			(stroke
				(width 0.1)
				(type default)
			)
			(layer "F.Fab")
		)
		(fp_line
			(start -0.12065 -0.305054)
			(end -0.12065 -0.2794)
			(stroke
				(width 0.1)
				(type default)
			)
			(layer "F.Fab")
		)
		(pad "1" smd circle
			(at -0.40005 0 270)
			(size 0 0)
			(layers "F.Cu" "F.Mask" "F.Paste")
			(net "GPU_FPGA_RST_R1_BUF_N")
		)
		(pad "2" smd circle
			(at 0.40005 0 270)
			(size 0 0)
			(layers "F.Cu" "F.Mask" "F.Paste")
			(net "GPU_FPGA_RST_R_BUF_N")
		)
	)
)
